(kicad_pcb
	(version 20221018)
	(generator pcbnew)
	(general
    (thickness 1.7403)
  )
	(paper "A4")
	(title_block
    (title "Data Center RDIMM DDR4 Tester")
    (date "2024-09-30")
    (rev "1.2.4")
		(comment 9 "footprint 169 of 690 (U14), pads 225-291 of 291")
	)
	(layers
    (0 "F.Cu" signal)
    (1 "In1.Cu" power)
    (2 "In2.Cu" signal)
    (3 "In3.Cu" power)
    (4 "In4.Cu" power)
    (5 "In5.Cu" signal)
    (6 "In6.Cu" power)
    (7 "In7.Cu" signal)
    (8 "In8.Cu" power)
    (9 "In9.Cu" signal)
    (10 "In10.Cu" power)
    (31 "B.Cu" signal)
    (32 "B.Adhes" user "B.Adhesive")
    (33 "F.Adhes" user "F.Adhesive")
    (34 "B.Paste" user)
    (35 "F.Paste" user)
    (36 "B.SilkS" user "B.Silkscreen")
    (37 "F.SilkS" user "F.Silkscreen")
    (38 "B.Mask" user)
    (39 "F.Mask" user)
    (40 "Dwgs.User" user "User.Drawings")
    (41 "Cmts.User" user "User.Comments")
    (42 "Eco1.User" user "User.Eco1")
    (43 "Eco2.User" user "User.Eco2")
    (44 "Edge.Cuts" user)
    (45 "Margin" user)
    (46 "B.CrtYd" user "B.Courtyard")
    (47 "F.CrtYd" user "F.Courtyard")
    (48 "B.Fab" user)
    (49 "F.Fab" user)
  )
	(footprint "data-center-rdimm-ddr4-tester-footprints:Bus_DDR4_Socket_DIMM_2199155-1"
    (layer "F.Cu")
    (at 246.636328 55.060008 180)
    (property "Author" "Antmicro")
    (property "License" "Apache-2.0")
    (property "MPN" "2199155-1")
    (property "Manufacturer" "TE Connectivity")
    (property "Sheetfile" "DDR4.kicad_sch")
    (property "Sheetname" "DDR4")
    (property "ki_description" "DDR4 RDIMM 288 Pin SMT type")
    (attr smd)
    (fp_text reference "U14" (at -5.583672 1.360008 180) (layer "F.SilkS")
        (effects (font (size 0.7 0.7) (thickness 0.15)) (justify left bottom))
    )
    (fp_text value "Bus_DDR4_2199155-1" (at -7.9 2.3 180) (layer "F.Fab") hide
        (effects (font (size 0.7 0.7) (thickness 0.15)) (justify left bottom))
    )
    (pad "225" smd rect (at 73.099 -4.601 270) (size 1.8 0.57) (layers "F.Cu" "F.Paste" "F.Mask")
      (net 208 "A10\\AP") (pinfunction "A10/AP") (pintype "passive"))
    (pad "226" smd rect (at 73.95 -4.601 270) (size 1.8 0.57) (layers "F.Cu" "F.Paste" "F.Mask")
      (net 77 "VDDQ") (pinfunction "VDD") (pintype "passive"))
    (pad "227" smd rect (at 74.799 -4.601 270) (size 1.8 0.57) (layers "F.Cu" "F.Paste" "F.Mask")
      (net 707 "unconnected-(U14B-RFU-Pad227)") (pinfunction "RFU") (pintype "no_connect"))
    (pad "228" smd rect (at 75.65 -4.601 270) (size 1.8 0.57) (layers "F.Cu" "F.Paste" "F.Mask")
      (net 210 "~{WE}\\A14") (pinfunction "WE_n/A14") (pintype "passive"))
    (pad "229" smd rect (at 76.498 -4.601 270) (size 1.8 0.57) (layers "F.Cu" "F.Paste" "F.Mask")
      (net 77 "VDDQ") (pinfunction "VDD") (pintype "passive"))
    (pad "230" smd rect (at 77.349 -4.601 270) (size 1.8 0.57) (layers "F.Cu" "F.Paste" "F.Mask")
      (net 209 "~{SAVE}") (pinfunction "SAVE_n") (pintype "passive"))
    (pad "231" smd rect (at 78.2 -4.601 270) (size 1.8 0.57) (layers "F.Cu" "F.Paste" "F.Mask")
      (net 77 "VDDQ") (pinfunction "VDD") (pintype "passive"))
    (pad "232" smd rect (at 79.049 -4.601 270) (size 1.8 0.57) (layers "F.Cu" "F.Paste" "F.Mask")
      (net 207 "A13") (pinfunction "A13") (pintype "passive"))
    (pad "233" smd rect (at 79.9 -4.601 270) (size 1.8 0.57) (layers "F.Cu" "F.Paste" "F.Mask")
      (net 77 "VDDQ") (pinfunction "VDD") (pintype "passive"))
    (pad "234" smd rect (at 80.748 -4.601 270) (size 1.8 0.57) (layers "F.Cu" "F.Paste" "F.Mask")
      (net 200 "A17") (pinfunction "NC/A17") (pintype "passive"))
    (pad "235" smd rect (at 81.599 -4.601 270) (size 1.8 0.57) (layers "F.Cu" "F.Paste" "F.Mask")
      (net 201 "NC\\C2") (pinfunction "NC/C2") (pintype "passive"))
    (pad "236" smd rect (at 82.45 -4.601 270) (size 1.8 0.57) (layers "F.Cu" "F.Paste" "F.Mask")
      (net 77 "VDDQ") (pinfunction "VDD") (pintype "passive"))
    (pad "237" smd rect (at 83.299 -4.601 270) (size 1.8 0.57) (layers "F.Cu" "F.Paste" "F.Mask")
      (net 198 "~{CS3}\\C1,NC") (pinfunction "CS3_n/C1") (pintype "passive"))
    (pad "238" smd rect (at 84.15 -4.601 270) (size 1.8 0.57) (layers "F.Cu" "F.Paste" "F.Mask")
      (net 195 "SA2") (pinfunction "SA2") (pintype "passive"))
    (pad "239" smd rect (at 84.998 -4.601 270) (size 1.8 0.57) (layers "F.Cu" "F.Paste" "F.Mask")
      (net 9 "GND") (pinfunction "VSS") (pintype "passive"))
    (pad "240" smd rect (at 85.849 -4.601 270) (size 1.8 0.57) (layers "F.Cu" "F.Paste" "F.Mask")
      (net 212 "DQ37") (pinfunction "DQ37") (pintype "passive"))
    (pad "241" smd rect (at 86.7 -4.601 270) (size 1.8 0.57) (layers "F.Cu" "F.Paste" "F.Mask")
      (net 9 "GND") (pinfunction "VSS") (pintype "passive"))
    (pad "242" smd rect (at 87.549 -4.601 270) (size 1.8 0.57) (layers "F.Cu" "F.Paste" "F.Mask")
      (net 194 "DQ33") (pinfunction "DQ33") (pintype "passive"))
    (pad "243" smd rect (at 88.4 -4.601 270) (size 1.8 0.57) (layers "F.Cu" "F.Paste" "F.Mask")
      (net 9 "GND") (pinfunction "VSS") (pintype "passive"))
    (pad "244" smd rect (at 89.248 -4.601 270) (size 1.8 0.57) (layers "F.Cu" "F.Paste" "F.Mask")
      (net 332 "DQS4_N") (pinfunction "DQS4_c") (pintype "passive"))
    (pad "245" smd rect (at 90.099 -4.601 270) (size 1.8 0.57) (layers "F.Cu" "F.Paste" "F.Mask")
      (net 330 "DQS4_P") (pinfunction "DQS4_t") (pintype "passive"))
    (pad "246" smd rect (at 90.95 -4.601 270) (size 1.8 0.57) (layers "F.Cu" "F.Paste" "F.Mask")
      (net 9 "GND") (pinfunction "VSS") (pintype "passive"))
    (pad "247" smd rect (at 91.799 -4.601 270) (size 1.8 0.57) (layers "F.Cu" "F.Paste" "F.Mask")
      (net 202 "DQ39") (pinfunction "DQ39") (pintype "passive"))
    (pad "248" smd rect (at 92.65 -4.601 270) (size 1.8 0.57) (layers "F.Cu" "F.Paste" "F.Mask")
      (net 9 "GND") (pinfunction "VSS") (pintype "passive"))
    (pad "249" smd rect (at 93.498 -4.601 270) (size 1.8 0.57) (layers "F.Cu" "F.Paste" "F.Mask")
      (net 213 "DQ35") (pinfunction "DQ35") (pintype "passive"))
    (pad "250" smd rect (at 94.349 -4.601 270) (size 1.8 0.57) (layers "F.Cu" "F.Paste" "F.Mask")
      (net 9 "GND") (pinfunction "VSS") (pintype "passive"))
    (pad "251" smd rect (at 95.2 -4.601 270) (size 1.8 0.57) (layers "F.Cu" "F.Paste" "F.Mask")
      (net 203 "DQ45") (pinfunction "DQ45") (pintype "passive"))
    (pad "252" smd rect (at 96.049 -4.601 270) (size 1.8 0.57) (layers "F.Cu" "F.Paste" "F.Mask")
      (net 9 "GND") (pinfunction "VSS") (pintype "passive"))
    (pad "253" smd rect (at 96.9 -4.601 270) (size 1.8 0.57) (layers "F.Cu" "F.Paste" "F.Mask")
      (net 189 "DQ41") (pinfunction "DQ41") (pintype "passive"))
    (pad "254" smd rect (at 97.748 -4.601 270) (size 1.8 0.57) (layers "F.Cu" "F.Paste" "F.Mask")
      (net 9 "GND") (pinfunction "VSS") (pintype "passive"))
    (pad "255" smd rect (at 98.599 -4.601 270) (size 1.8 0.57) (layers "F.Cu" "F.Paste" "F.Mask")
      (net 336 "DQS5_N") (pinfunction "DQS5_c") (pintype "passive"))
    (pad "256" smd rect (at 99.45 -4.601 270) (size 1.8 0.57) (layers "F.Cu" "F.Paste" "F.Mask")
      (net 334 "DQS5_P") (pinfunction "DQS5_t") (pintype "passive"))
    (pad "257" smd rect (at 100.299 -4.601 270) (size 1.8 0.57) (layers "F.Cu" "F.Paste" "F.Mask")
      (net 9 "GND") (pinfunction "VSS") (pintype "passive"))
    (pad "258" smd rect (at 101.15 -4.601 270) (size 1.8 0.57) (layers "F.Cu" "F.Paste" "F.Mask")
      (net 205 "DQ47") (pinfunction "DQ47") (pintype "passive"))
    (pad "259" smd rect (at 101.998 -4.601 270) (size 1.8 0.57) (layers "F.Cu" "F.Paste" "F.Mask")
      (net 9 "GND") (pinfunction "VSS") (pintype "passive"))
    (pad "260" smd rect (at 102.849 -4.601 270) (size 1.8 0.57) (layers "F.Cu" "F.Paste" "F.Mask")
      (net 188 "DQ43") (pinfunction "DQ43") (pintype "passive"))
    (pad "261" smd rect (at 103.7 -4.601 270) (size 1.8 0.57) (layers "F.Cu" "F.Paste" "F.Mask")
      (net 9 "GND") (pinfunction "VSS") (pintype "passive"))
    (pad "262" smd rect (at 104.549 -4.601 270) (size 1.8 0.57) (layers "F.Cu" "F.Paste" "F.Mask")
      (net 204 "DQ53") (pinfunction "DQ53") (pintype "passive"))
    (pad "263" smd rect (at 105.4 -4.601 270) (size 1.8 0.57) (layers "F.Cu" "F.Paste" "F.Mask")
      (net 9 "GND") (pinfunction "VSS") (pintype "passive"))
    (pad "264" smd rect (at 106.248 -4.601 270) (size 1.8 0.57) (layers "F.Cu" "F.Paste" "F.Mask")
      (net 190 "DQ49") (pinfunction "DQ49") (pintype "passive"))
    (pad "265" smd rect (at 107.099 -4.601 270) (size 1.8 0.57) (layers "F.Cu" "F.Paste" "F.Mask")
      (net 9 "GND") (pinfunction "VSS") (pintype "passive"))
    (pad "266" smd rect (at 107.95 -4.601 270) (size 1.8 0.57) (layers "F.Cu" "F.Paste" "F.Mask")
      (net 340 "DQS6_N") (pinfunction "DQS6_c") (pintype "passive"))
    (pad "267" smd rect (at 108.799 -4.601 270) (size 1.8 0.57) (layers "F.Cu" "F.Paste" "F.Mask")
      (net 338 "DQS6_P") (pinfunction "DQS6_t") (pintype "passive"))
    (pad "268" smd rect (at 109.65 -4.601 270) (size 1.8 0.57) (layers "F.Cu" "F.Paste" "F.Mask")
      (net 9 "GND") (pinfunction "VSS") (pintype "passive"))
    (pad "269" smd rect (at 110.498 -4.601 270) (size 1.8 0.57) (layers "F.Cu" "F.Paste" "F.Mask")
      (net 206 "DQ55") (pinfunction "DQ55") (pintype "passive"))
    (pad "270" smd rect (at 111.349 -4.601 270) (size 1.8 0.57) (layers "F.Cu" "F.Paste" "F.Mask")
      (net 9 "GND") (pinfunction "VSS") (pintype "passive"))
    (pad "271" smd rect (at 112.2 -4.601 270) (size 1.8 0.57) (layers "F.Cu" "F.Paste" "F.Mask")
      (net 193 "DQ51") (pinfunction "DQ51") (pintype "passive"))
    (pad "272" smd rect (at 113.049 -4.601 270) (size 1.8 0.57) (layers "F.Cu" "F.Paste" "F.Mask")
      (net 9 "GND") (pinfunction "VSS") (pintype "passive"))
    (pad "273" smd rect (at 113.9 -4.601 270) (size 1.8 0.57) (layers "F.Cu" "F.Paste" "F.Mask")
      (net 191 "DQ61") (pinfunction "DQ61") (pintype "passive"))
    (pad "274" smd rect (at 114.749 -4.601 270) (size 1.8 0.57) (layers "F.Cu" "F.Paste" "F.Mask")
      (net 9 "GND") (pinfunction "VSS") (pintype "passive"))
    (pad "275" smd rect (at 115.599 -4.601 270) (size 1.8 0.57) (layers "F.Cu" "F.Paste" "F.Mask")
      (net 192 "DQ57") (pinfunction "DQ57") (pintype "passive"))
    (pad "276" smd rect (at 116.45 -4.601 270) (size 1.8 0.57) (layers "F.Cu" "F.Paste" "F.Mask")
      (net 9 "GND") (pinfunction "VSS") (pintype "passive"))
    (pad "277" smd rect (at 117.299 -4.601 270) (size 1.8 0.57) (layers "F.Cu" "F.Paste" "F.Mask")
      (net 344 "DQS7_N") (pinfunction "DQS7_c") (pintype "passive"))
    (pad "278" smd rect (at 118.15 -4.601 270) (size 1.8 0.57) (layers "F.Cu" "F.Paste" "F.Mask")
      (net 342 "DQS7_P") (pinfunction "DQS7_t") (pintype "passive"))
    (pad "279" smd rect (at 118.999 -4.601 270) (size 1.8 0.57) (layers "F.Cu" "F.Paste" "F.Mask")
      (net 9 "GND") (pinfunction "VSS") (pintype "passive"))
    (pad "280" smd rect (at 119.849 -4.601 270) (size 1.8 0.57) (layers "F.Cu" "F.Paste" "F.Mask")
      (net 197 "DQ63") (pinfunction "DQ63") (pintype "passive"))
    (pad "281" smd rect (at 120.7 -4.601 270) (size 1.8 0.57) (layers "F.Cu" "F.Paste" "F.Mask")
      (net 9 "GND") (pinfunction "VSS") (pintype "passive"))
    (pad "282" smd rect (at 121.549 -4.601 270) (size 1.8 0.57) (layers "F.Cu" "F.Paste" "F.Mask")
      (net 196 "DQ59") (pinfunction "DQ59") (pintype "passive"))
    (pad "283" smd rect (at 122.4 -4.601 270) (size 1.8 0.57) (layers "F.Cu" "F.Paste" "F.Mask")
      (net 9 "GND") (pinfunction "VSS") (pintype "passive"))
    (pad "284" smd rect (at 123.249 -4.601 270) (size 1.8 0.57) (layers "F.Cu" "F.Paste" "F.Mask")
      (net 185 "VDDSPD") (pinfunction "VDDSPD") (pintype "passive"))
    (pad "285" smd rect (at 124.099 -4.601 270) (size 1.8 0.57) (layers "F.Cu" "F.Paste" "F.Mask")
      (net 350 "SDA_2V5") (pinfunction "SDA") (pintype "passive"))
    (pad "286" smd rect (at 124.95 -4.601 270) (size 1.8 0.57) (layers "F.Cu" "F.Paste" "F.Mask")
      (net 184 "VPP") (pinfunction "VPP") (pintype "passive"))
    (pad "287" smd rect (at 125.799 -4.601 270) (size 1.8 0.57) (layers "F.Cu" "F.Paste" "F.Mask")
      (net 184 "VPP") (pinfunction "VPP") (pintype "passive"))
    (pad "288" smd rect (at 126.65 -4.601 270) (size 1.8 0.57) (layers "F.Cu" "F.Paste" "F.Mask")
      (net 184 "VPP") (pinfunction "VPP") (pintype "passive"))
    (pad "MP1" thru_hole roundrect (at -5.651 -2.301) (size 1.8 3.05) (drill oval 1.2 2.45) (layers "*.Cu" "*.Mask") (roundrect_rratio 0.5)
      (net 708 "unconnected-(U14B-MP-PadMP1)") (pinfunction "MP") (pintype "passive+no_connect"))
    (pad "MP2" thru_hole roundrect (at 68.9 -2.301) (size 1.8 3.05) (drill oval 1.2 2.45) (layers "*.Cu" "*.Mask") (roundrect_rratio 0.5)
      (net 709 "unconnected-(U14B-MP-PadMP2)") (pinfunction "MP") (pintype "passive+no_connect"))
    (pad "MP3" thru_hole roundrect (at 132.3 -2.301) (size 1.8 3.05) (drill oval 1.2 2.45) (layers "*.Cu" "*.Mask") (roundrect_rratio 0.5)
      (net 710 "unconnected-(U14B-MP-PadMP3)") (pinfunction "MP") (pintype "passive+no_connect"))
  )
)
